(kicad_pcb
	(version 20260206)
	(generator "pcbnew")
	(generator_version "10.0")
	(general
		(thickness 1.6)
		(legacy_teardrops no)
	)
	(paper "A4")
	(title_block
		(title "12092022_DA0F0TMDCD0_F0T_Management_Board_D_brd_V3_OCP.brd")
		(comment 1 "Grand Teton / footprints 528-533 of 1440")
	)
	(layers
		(0 "F.Cu" signal "TOP")
		(4 "In1.Cu" signal "GND")
		(6 "In2.Cu" signal "IN1")
		(8 "In3.Cu" signal "GND1")
		(10 "In4.Cu" signal "IN2")
		(12 "In5.Cu" signal "VCC")
		(14 "In6.Cu" signal "VCC1")
		(16 "In7.Cu" signal "IN3")
		(18 "In8.Cu" signal "GND2")
		(20 "In9.Cu" signal "IN4")
		(22 "In10.Cu" signal "GND3")
		(2 "B.Cu" signal "BOTTOM")
		(9 "F.Adhes" user "F.Adhesive")
		(11 "B.Adhes" user "B.Adhesive")
		(13 "F.Paste" user "Package Geometry/Pastemask Top")
		(15 "B.Paste" user "Package Geometry/Pastemask Bottom")
		(5 "F.SilkS" user "Ref Des/Silkscreen Top")
		(7 "B.SilkS" user "Ref Des/Silkscreen Bottom")
		(1 "F.Mask" user "Board Geometry/Soldermask Top")
		(3 "B.Mask" user "Board Geometry/Soldermask Bottom")
		(17 "Dwgs.User" user "User.Drawings")
		(19 "Cmts.User" user "User.Comments")
		(21 "Eco1.User" user "User.Eco1")
		(23 "Eco2.User" user "User.Eco2")
		(25 "Edge.Cuts" user "Board Geometry/Outline")
		(27 "Margin" user)
		(31 "F.CrtYd" user "Package Geometry/Place Bound Top")
		(29 "B.CrtYd" user "Package Geometry/Place Bound Bottom")
		(35 "F.Fab" user "Ref Des/Assembly Top")
		(33 "B.Fab" user "Ref Des/Assembly Bottom")
	)
	(footprint ""
		(layer "F.Cu")
		(at 25.273 -68.834 90)
		(property "Reference" "R543"
			(at 0 0 90)
			(layer "F.SilkS")
			(hide yes)
			(effects
				(font
					(size 1.27 1.27)
				)
			)
		)
		(property "Value" ""
			(at 0 0 90)
			(layer "F.Fab")
			(effects
				(font
					(size 1.27 1.27)
				)
			)
		)
		(duplicate_pad_numbers_are_jumpers no)
		(fp_line
			(start 0.7874 -0.4064)
			(end 0.7874 0.4064)
			(stroke
				(width 0.1524)
				(type default)
			)
			(layer "F.SilkS")
		)
		(fp_line
			(start -0.7874 -0.4064)
			(end 0.7874 -0.4064)
			(stroke
				(width 0.1524)
				(type default)
			)
			(layer "F.SilkS")
		)
		(fp_line
			(start 0.7874 0.4064)
			(end -0.7874 0.4064)
			(stroke
				(width 0.1524)
				(type default)
			)
			(layer "F.SilkS")
		)
		(fp_line
			(start -0.7874 0.4064)
			(end -0.7874 -0.4064)
			(stroke
				(width 0.1524)
				(type default)
			)
			(layer "F.SilkS")
		)
		(fp_line
			(start -0.12065 -0.305054)
			(end -0.12065 -0.2794)
			(stroke
				(width 0.1)
				(type default)
			)
			(layer "F.Fab")
		)
		(fp_line
			(start -0.67945 -0.305054)
			(end -0.12065 -0.305054)
			(stroke
				(width 0.1)
				(type default)
			)
			(layer "F.Fab")
		)
		(fp_line
			(start 0.67945 -0.3048)
			(end 0.67945 0.3048)
			(stroke
				(width 0.1)
				(type default)
			)
			(layer "F.Fab")
		)
		(fp_line
			(start 0.12065 -0.3048)
			(end 0.67945 -0.3048)
			(stroke
				(width 0.1)
				(type default)
			)
			(layer "F.Fab")
		)
		(fp_line
			(start 0.12065 -0.2794)
			(end 0.12065 -0.3048)
			(stroke
				(width 0.1)
				(type default)
			)
			(layer "F.Fab")
		)
		(fp_line
			(start -0.12065 -0.2794)
			(end 0.12065 -0.2794)
			(stroke
				(width 0.1)
				(type default)
			)
			(layer "F.Fab")
		)
		(fp_line
			(start 0.120396 0.2794)
			(end -0.12065 0.2794)
			(stroke
				(width 0.1)
				(type default)
			)
			(layer "F.Fab")
		)
		(fp_line
			(start -0.12065 0.2794)
			(end -0.12065 0.3048)
			(stroke
				(width 0.1)
				(type default)
			)
			(layer "F.Fab")
		)
		(fp_line
			(start 0.67945 0.3048)
			(end 0.120396 0.3048)
			(stroke
				(width 0.1)
				(type default)
			)
			(layer "F.Fab")
		)
		(fp_line
			(start 0.120396 0.3048)
			(end 0.120396 0.2794)
			(stroke
				(width 0.1)
				(type default)
			)
			(layer "F.Fab")
		)
		(fp_line
			(start -0.12065 0.3048)
			(end -0.67945 0.3048)
			(stroke
				(width 0.1)
				(type default)
			)
			(layer "F.Fab")
		)
		(fp_line
			(start -0.67945 0.3048)
			(end -0.67945 -0.305054)
			(stroke
				(width 0.1)
				(type default)
			)
			(layer "F.Fab")
		)
		(pad "1" smd circle
			(at -0.40005 0 90)
			(size 0 0)
			(layers "F.Cu" "F.Mask" "F.Paste")
			(net "P3V3_AUX")
		)
		(pad "2" smd circle
			(at 0.40005 0 90)
			(size 0 0)
			(layers "F.Cu" "F.Mask" "F.Paste")
			(net "SPI_BMC_HOLD1_N")
		)
	)
	(footprint ""
		(layer "F.Cu")
		(at 65.618106 -29.377132 -90)
		(property "Reference" "R218"
			(at 0 0 270)
			(layer "F.SilkS")
			(hide yes)
			(effects
				(font
					(size 1.27 1.27)
				)
			)
		)
		(property "Value" ""
			(at 0 0 270)
			(layer "F.Fab")
			(effects
				(font
					(size 1.27 1.27)
				)
			)
		)
		(duplicate_pad_numbers_are_jumpers no)
		(fp_line
			(start 0.458978 0.4064)
			(end -0.397002 0.4064)
			(stroke
				(width 0.1524)
				(type default)
			)
			(layer "F.SilkS")
		)
		(fp_line
			(start -0.7874 0.060706)
			(end -0.7874 -0.4064)
			(stroke
				(width 0.1524)
				(type default)
			)
			(layer "F.SilkS")
		)
		(fp_line
			(start -0.7874 -0.4064)
			(end 0.7874 -0.4064)
			(stroke
				(width 0.1524)
				(type default)
			)
			(layer "F.SilkS")
		)
		(fp_line
			(start 0.7874 -0.4064)
			(end 0.7874 -0.010414)
			(stroke
				(width 0.1524)
				(type default)
			)
			(layer "F.SilkS")
		)
		(fp_line
			(start -0.67945 0.3048)
			(end -0.67945 -0.305054)
			(stroke
				(width 0.1)
				(type default)
			)
			(layer "F.Fab")
		)
		(fp_line
			(start -0.12065 0.3048)
			(end -0.67945 0.3048)
			(stroke
				(width 0.1)
				(type default)
			)
			(layer "F.Fab")
		)
		(fp_line
			(start 0.120396 0.3048)
			(end 0.120396 0.2794)
			(stroke
				(width 0.1)
				(type default)
			)
			(layer "F.Fab")
		)
		(fp_line
			(start 0.67945 0.3048)
			(end 0.120396 0.3048)
			(stroke
				(width 0.1)
				(type default)
			)
			(layer "F.Fab")
		)
		(fp_line
			(start -0.12065 0.2794)
			(end -0.12065 0.3048)
			(stroke
				(width 0.1)
				(type default)
			)
			(layer "F.Fab")
		)
		(fp_line
			(start 0.120396 0.2794)
			(end -0.12065 0.2794)
			(stroke
				(width 0.1)
				(type default)
			)
			(layer "F.Fab")
		)
		(fp_line
			(start -0.12065 -0.2794)
			(end 0.12065 -0.2794)
			(stroke
				(width 0.1)
				(type default)
			)
			(layer "F.Fab")
		)
		(fp_line
			(start 0.12065 -0.2794)
			(end 0.12065 -0.3048)
			(stroke
				(width 0.1)
				(type default)
			)
			(layer "F.Fab")
		)
		(fp_line
			(start 0.12065 -0.3048)
			(end 0.67945 -0.3048)
			(stroke
				(width 0.1)
				(type default)
			)
			(layer "F.Fab")
		)
		(fp_line
			(start 0.67945 -0.3048)
			(end 0.67945 0.3048)
			(stroke
				(width 0.1)
				(type default)
			)
			(layer "F.Fab")
		)
		(fp_line
			(start -0.67945 -0.305054)
			(end -0.12065 -0.305054)
			(stroke
				(width 0.1)
				(type default)
			)
			(layer "F.Fab")
		)
		(fp_line
			(start -0.12065 -0.305054)
			(end -0.12065 -0.2794)
			(stroke
				(width 0.1)
				(type default)
			)
			(layer "F.Fab")
		)
		(pad "1" smd circle
			(at -0.40005 0 270)
			(size 0 0)
			(layers "F.Cu" "F.Mask" "F.Paste")
			(net "USB_HOST_BMC_A_R_DN")
		)
		(pad "2" smd circle
			(at 0.40005 0 270)
			(size 0 0)
			(layers "F.Cu" "F.Mask" "F.Paste")
			(net "USB_HOST_BMC_A_DN")
		)
	)
	(footprint ""
		(layer "F.Cu")
		(at 32.893 -36.195 90)
		(property "Reference" "R451"
			(at 0 0 90)
			(layer "F.SilkS")
			(hide yes)
			(effects
				(font
					(size 1.27 1.27)
				)
			)
		)
		(property "Value" ""
			(at 0 0 90)
			(layer "F.Fab")
			(effects
				(font
					(size 1.27 1.27)
				)
			)
		)
		(duplicate_pad_numbers_are_jumpers no)
		(fp_line
			(start 0.7874 -0.4064)
			(end 0.7874 0.4064)
			(stroke
				(width 0.1524)
				(type default)
			)
			(layer "F.SilkS")
		)
		(fp_line
			(start -0.7874 -0.4064)
			(end 0.7874 -0.4064)
			(stroke
				(width 0.1524)
				(type default)
			)
			(layer "F.SilkS")
		)
		(fp_line
			(start 0.7874 0.4064)
			(end -0.7874 0.4064)
			(stroke
				(width 0.1524)
				(type default)
			)
			(layer "F.SilkS")
		)
		(fp_line
			(start -0.7874 0.4064)
			(end -0.7874 -0.4064)
			(stroke
				(width 0.1524)
				(type default)
			)
			(layer "F.SilkS")
		)
		(fp_line
			(start -0.12065 -0.305054)
			(end -0.12065 -0.2794)
			(stroke
				(width 0.1)
				(type default)
			)
			(layer "F.Fab")
		)
		(fp_line
			(start -0.67945 -0.305054)
			(end -0.12065 -0.305054)
			(stroke
				(width 0.1)
				(type default)
			)
			(layer "F.Fab")
		)
		(fp_line
			(start 0.67945 -0.3048)
			(end 0.67945 0.3048)
			(stroke
				(width 0.1)
				(type default)
			)
			(layer "F.Fab")
		)
		(fp_line
			(start 0.12065 -0.3048)
			(end 0.67945 -0.3048)
			(stroke
				(width 0.1)
				(type default)
			)
			(layer "F.Fab")
		)
		(fp_line
			(start 0.12065 -0.2794)
			(end 0.12065 -0.3048)
			(stroke
				(width 0.1)
				(type default)
			)
			(layer "F.Fab")
		)
		(fp_line
			(start -0.12065 -0.2794)
			(end 0.12065 -0.2794)
			(stroke
				(width 0.1)
				(type default)
			)
			(layer "F.Fab")
		)
		(fp_line
			(start 0.120396 0.2794)
			(end -0.12065 0.2794)
			(stroke
				(width 0.1)
				(type default)
			)
			(layer "F.Fab")
		)
		(fp_line
			(start -0.12065 0.2794)
			(end -0.12065 0.3048)
			(stroke
				(width 0.1)
				(type default)
			)
			(layer "F.Fab")
		)
		(fp_line
			(start 0.67945 0.3048)
			(end 0.120396 0.3048)
			(stroke
				(width 0.1)
				(type default)
			)
			(layer "F.Fab")
		)
		(fp_line
			(start 0.120396 0.3048)
			(end 0.120396 0.2794)
			(stroke
				(width 0.1)
				(type default)
			)
			(layer "F.Fab")
		)
		(fp_line
			(start -0.12065 0.3048)
			(end -0.67945 0.3048)
			(stroke
				(width 0.1)
				(type default)
			)
			(layer "F.Fab")
		)
		(fp_line
			(start -0.67945 0.3048)
			(end -0.67945 -0.305054)
			(stroke
				(width 0.1)
				(type default)
			)
			(layer "F.Fab")
		)
		(pad "1" smd circle
			(at -0.40005 0 90)
			(size 0 0)
			(layers "F.Cu" "F.Mask" "F.Paste")
			(net "PWRGD_P1V0_AUX_DELAY")
		)
		(pad "2" smd circle
			(at 0.40005 0 90)
			(size 0 0)
			(layers "F.Cu" "F.Mask" "F.Paste")
			(net "PWRGD_P1V0_AUX_DELAY_R1")
		)
	)
	(footprint ""
		(layer "F.Cu")
		(at 43.948604 -87.679784 90)
		(property "Reference" "R484"
			(at 0 0 90)
			(layer "F.SilkS")
			(hide yes)
			(effects
				(font
					(size 1.27 1.27)
				)
			)
		)
		(property "Value" ""
			(at 0 0 90)
			(layer "F.Fab")
			(effects
				(font
					(size 1.27 1.27)
				)
			)
		)
		(duplicate_pad_numbers_are_jumpers no)
		(fp_line
			(start 0.7874 -0.4064)
			(end 0.7874 0.4064)
			(stroke
				(width 0.1524)
				(type default)
			)
			(layer "F.SilkS")
		)
		(fp_line
			(start -0.7874 -0.4064)
			(end 0.7874 -0.4064)
			(stroke
				(width 0.1524)
				(type default)
			)
			(layer "F.SilkS")
		)
		(fp_line
			(start 0.7874 0.4064)
			(end -0.7874 0.4064)
			(stroke
				(width 0.1524)
				(type default)
			)
			(layer "F.SilkS")
		)
		(fp_line
			(start -0.7874 0.4064)
			(end -0.7874 -0.4064)
			(stroke
				(width 0.1524)
				(type default)
			)
			(layer "F.SilkS")
		)
		(fp_line
			(start -0.12065 -0.305054)
			(end -0.12065 -0.2794)
			(stroke
				(width 0.1)
				(type default)
			)
			(layer "F.Fab")
		)
		(fp_line
			(start -0.67945 -0.305054)
			(end -0.12065 -0.305054)
			(stroke
				(width 0.1)
				(type default)
			)
			(layer "F.Fab")
		)
		(fp_line
			(start 0.67945 -0.3048)
			(end 0.67945 0.3048)
			(stroke
				(width 0.1)
				(type default)
			)
			(layer "F.Fab")
		)
		(fp_line
			(start 0.12065 -0.3048)
			(end 0.67945 -0.3048)
			(stroke
				(width 0.1)
				(type default)
			)
			(layer "F.Fab")
		)
		(fp_line
			(start 0.12065 -0.2794)
			(end 0.12065 -0.3048)
			(stroke
				(width 0.1)
				(type default)
			)
			(layer "F.Fab")
		)
		(fp_line
			(start -0.12065 -0.2794)
			(end 0.12065 -0.2794)
			(stroke
				(width 0.1)
				(type default)
			)
			(layer "F.Fab")
		)
		(fp_line
			(start 0.120396 0.2794)
			(end -0.12065 0.2794)
			(stroke
				(width 0.1)
				(type default)
			)
			(layer "F.Fab")
		)
		(fp_line
			(start -0.12065 0.2794)
			(end -0.12065 0.3048)
			(stroke
				(width 0.1)
				(type default)
			)
			(layer "F.Fab")
		)
		(fp_line
			(start 0.67945 0.3048)
			(end 0.120396 0.3048)
			(stroke
				(width 0.1)
				(type default)
			)
			(layer "F.Fab")
		)
		(fp_line
			(start 0.120396 0.3048)
			(end 0.120396 0.2794)
			(stroke
				(width 0.1)
				(type default)
			)
			(layer "F.Fab")
		)
		(fp_line
			(start -0.12065 0.3048)
			(end -0.67945 0.3048)
			(stroke
				(width 0.1)
				(type default)
			)
			(layer "F.Fab")
		)
		(fp_line
			(start -0.67945 0.3048)
			(end -0.67945 -0.305054)
			(stroke
				(width 0.1)
				(type default)
			)
			(layer "F.Fab")
		)
		(pad "1" smd circle
			(at -0.40005 0 90)
			(size 0 0)
			(layers "F.Cu" "F.Mask" "F.Paste")
			(net "SPI_PCH_MUXED_IO1")
		)
		(pad "2" smd circle
			(at 0.40005 0 90)
			(size 0 0)
			(layers "F.Cu" "F.Mask" "F.Paste")
			(net "SPI_PCH_IO1_FLASH_R1")
		)
	)
	(footprint ""
		(layer "F.Cu")
		(at 24.257 -68.834 90)
		(property "Reference" "R404"
			(at 0 0 90)
			(layer "F.SilkS")
			(hide yes)
			(effects
				(font
					(size 1.27 1.27)
				)
			)
		)
		(property "Value" ""
			(at 0 0 90)
			(layer "F.Fab")
			(effects
				(font
					(size 1.27 1.27)
				)
			)
		)
		(duplicate_pad_numbers_are_jumpers no)
		(fp_line
			(start 0.7874 -0.4064)
			(end 0.7874 0.4064)
			(stroke
				(width 0.1524)
				(type default)
			)
			(layer "F.SilkS")
		)
		(fp_line
			(start -0.7874 -0.4064)
			(end 0.7874 -0.4064)
			(stroke
				(width 0.1524)
				(type default)
			)
			(layer "F.SilkS")
		)
		(fp_line
			(start 0.7874 0.4064)
			(end -0.7874 0.4064)
			(stroke
				(width 0.1524)
				(type default)
			)
			(layer "F.SilkS")
		)
		(fp_line
			(start -0.7874 0.4064)
			(end -0.7874 -0.4064)
			(stroke
				(width 0.1524)
				(type default)
			)
			(layer "F.SilkS")
		)
		(fp_line
			(start -0.12065 -0.305054)
			(end -0.12065 -0.2794)
			(stroke
				(width 0.1)
				(type default)
			)
			(layer "F.Fab")
		)
		(fp_line
			(start -0.67945 -0.305054)
			(end -0.12065 -0.305054)
			(stroke
				(width 0.1)
				(type default)
			)
			(layer "F.Fab")
		)
		(fp_line
			(start 0.67945 -0.3048)
			(end 0.67945 0.3048)
			(stroke
				(width 0.1)
				(type default)
			)
			(layer "F.Fab")
		)
		(fp_line
			(start 0.12065 -0.3048)
			(end 0.67945 -0.3048)
			(stroke
				(width 0.1)
				(type default)
			)
			(layer "F.Fab")
		)
		(fp_line
			(start 0.12065 -0.2794)
			(end 0.12065 -0.3048)
			(stroke
				(width 0.1)
				(type default)
			)
			(layer "F.Fab")
		)
		(fp_line
			(start -0.12065 -0.2794)
			(end 0.12065 -0.2794)
			(stroke
				(width 0.1)
				(type default)
			)
			(layer "F.Fab")
		)
		(fp_line
			(start 0.120396 0.2794)
			(end -0.12065 0.2794)
			(stroke
				(width 0.1)
				(type default)
			)
			(layer "F.Fab")
		)
		(fp_line
			(start -0.12065 0.2794)
			(end -0.12065 0.3048)
			(stroke
				(width 0.1)
				(type default)
			)
			(layer "F.Fab")
		)
		(fp_line
			(start 0.67945 0.3048)
			(end 0.120396 0.3048)
			(stroke
				(width 0.1)
				(type default)
			)
			(layer "F.Fab")
		)
		(fp_line
			(start 0.120396 0.3048)
			(end 0.120396 0.2794)
			(stroke
				(width 0.1)
				(type default)
			)
			(layer "F.Fab")
		)
		(fp_line
			(start -0.12065 0.3048)
			(end -0.67945 0.3048)
			(stroke
				(width 0.1)
				(type default)
			)
			(layer "F.Fab")
		)
		(fp_line
			(start -0.67945 0.3048)
			(end -0.67945 -0.305054)
			(stroke
				(width 0.1)
				(type default)
			)
			(layer "F.Fab")
		)
		(pad "1" smd circle
			(at -0.40005 0 90)
			(size 0 0)
			(layers "F.Cu" "F.Mask" "F.Paste")
			(net "P3V3_AUX")
		)
		(pad "2" smd circle
			(at 0.40005 0 90)
			(size 0 0)
			(layers "F.Cu" "F.Mask" "F.Paste")
			(net "BSM_PRSNT_N")
		)
	)
	(footprint ""
		(layer "F.Cu")
		(at 81.755996 -78.151228 180)
		(property "Reference" "PC251"
			(at 0 0 180)
			(layer "F.SilkS")
			(hide yes)
			(effects
				(font
					(size 1.27 1.27)
				)
			)
		)
		(property "Value" ""
			(at 0 0 180)
			(layer "F.Fab")
			(effects
				(font
					(size 1.27 1.27)
				)
			)
		)
		(duplicate_pad_numbers_are_jumpers no)
		(fp_line
			(start 1.651 0.8382)
			(end -1.651 0.8382)
			(stroke
				(width 0.1524)
				(type default)
			)
			(layer "F.SilkS")
		)
		(fp_line
			(start 1.651 -0.8382)
			(end 1.651 0.8382)
			(stroke
				(width 0.1524)
				(type default)
			)
			(layer "F.SilkS")
		)
		(fp_line
			(start 0 0.8382)
			(end 0 -0.8382)
			(stroke
				(width 0.1524)
				(type default)
			)
			(layer "F.SilkS")
		)
		(fp_line
			(start -1.651 0.8382)
			(end -1.651 -0.8382)
			(stroke
				(width 0.1524)
				(type default)
			)
			(layer "F.SilkS")
		)
		(fp_line
			(start -1.651 -0.8382)
			(end 1.651 -0.8382)
			(stroke
				(width 0.1524)
				(type default)
			)
			(layer "F.SilkS")
		)
		(fp_line
			(start 1.55956 0.7366)
			(end 1.55956 -0.7366)
			(stroke
				(width 0.1)
				(type default)
			)
			(layer "F.Fab")
		)
		(fp_line
			(start 1.55956 -0.7366)
			(end 1.524 -0.7366)
			(stroke
				(width 0.1)
				(type default)
			)
			(layer "F.Fab")
		)
		(fp_line
			(start 1.524 0.7366)
			(end 1.55956 0.7366)
			(stroke
				(width 0.1)
				(type default)
			)
			(layer "F.Fab")
		)
		(fp_line
			(start 1.524 -0.7366)
			(end -1.524 -0.7366)
			(stroke
				(width 0.1)
				(type default)
			)
			(layer "F.Fab")
		)
		(fp_line
			(start -1.524 0.7366)
			(end 1.524 0.7366)
			(stroke
				(width 0.1)
				(type default)
			)
			(layer "F.Fab")
		)
		(fp_line
			(start -1.524 -0.7366)
			(end -1.55956 -0.7366)
			(stroke
				(width 0.1)
				(type default)
			)
			(layer "F.Fab")
		)
		(fp_line
			(start -1.55956 0.7366)
			(end -1.524 0.7366)
			(stroke
				(width 0.1)
				(type default)
			)
			(layer "F.Fab")
		)
		(fp_line
			(start -1.55956 -0.7366)
			(end -1.55956 0.7366)
			(stroke
				(width 0.1)
				(type default)
			)
			(layer "F.Fab")
		)
		(pad "1" smd rect
			(at -0.94996 0)
			(size 1.1176 1.3716)
			(layers "F.Cu" "F.Mask" "F.Paste")
			(net "SW_P1V2_AUX_FLT")
		)
		(pad "2" smd rect
			(at 0.94996 0)
			(size 1.1176 1.3716)
			(layers "F.Cu" "F.Mask" "F.Paste")
			(net "GND")
		)
	)
)
